(kicad_pcb
	(version 20260206)
	(generator "pcbnew")
	(generator_version "10.0")
	(general
		(thickness 1.6)
		(legacy_teardrops no)
	)
	(paper "A4")
	(title_block
		(title "Bryce Canyon_IOM_M2_16342-2_OCP.brd")
		(comment 1 "Bryce Canyon / footprints 299-305 of 1146")
	)
	(layers
		(0 "F.Cu" signal "TOP")
		(4 "In1.Cu" signal "L2GND")
		(6 "In2.Cu" signal "L3")
		(8 "In3.Cu" signal "L4VCC")
		(10 "In4.Cu" signal "L5VCC")
		(12 "In5.Cu" signal "L6")
		(14 "In6.Cu" signal "L7GND")
		(2 "B.Cu" signal "BOTTOM")
		(9 "F.Adhes" user "F.Adhesive")
		(11 "B.Adhes" user "B.Adhesive")
		(13 "F.Paste" user "Package Geometry/Pastemask Top")
		(15 "B.Paste" user "Package Geometry/Pastemask Bottom")
		(5 "F.SilkS" user "Ref Des/Silkscreen Top")
		(7 "B.SilkS" user "Ref Des/Silkscreen Bottom")
		(1 "F.Mask" user "Board Geometry/Soldermask Top")
		(3 "B.Mask" user "Board Geometry/Soldermask Bottom")
		(17 "Dwgs.User" user "User.Drawings")
		(19 "Cmts.User" user "User.Comments")
		(21 "Eco1.User" user "User.Eco1")
		(23 "Eco2.User" user "User.Eco2")
		(25 "Edge.Cuts" user "Board Geometry/Outline")
		(27 "Margin" user)
		(31 "F.CrtYd" user "Package Geometry/Place Bound Top")
		(29 "B.CrtYd" user "Package Geometry/Place Bound Bottom")
		(35 "F.Fab" user "Ref Des/Assembly Top")
		(33 "B.Fab" user "Ref Des/Assembly Bottom")
	)
	(footprint ""
		(layer "F.Cu")
		(at 87.638636 -31.905448 180)
		(property "Reference" "C2"
			(at 0 0 180)
			(layer "F.SilkS")
			(hide yes)
			(effects
				(font
					(size 1.27 1.27)
				)
			)
		)
		(property "Value" "SC1U16V3KX-5GP"
			(at 0 -2.8194 180)
			(unlocked yes)
			(layer "F.Fab")
			(hide yes)
			(effects
				(font
					(size 1.016 1.016)
					(thickness 0.1524)
				)
			)
		)
		(property "Device Type" "C603H36"
			(at 0 -4.3434 180)
			(unlocked yes)
			(layer "F.Fab")
			(hide yes)
			(effects
				(font
					(size 1.016 1.016)
					(thickness 0.1524)
				)
			)
		)
		(duplicate_pad_numbers_are_jumpers no)
		(fp_line
			(start 0.508 0)
			(end -0.508 0)
			(stroke
				(width 0.2032)
				(type default)
			)
			(layer "F.SilkS")
		)
		(fp_rect
			(start -0.5842 1.3335)
			(end 0.5842 -1.3335)
			(stroke
				(width 0)
				(type default)
			)
			(fill no)
			(layer "F.CrtYd")
		)
		(fp_rect
			(start -0.5842 1.3335)
			(end 0.5842 -1.3335)
			(stroke
				(width 0)
				(type default)
			)
			(fill no)
			(layer "F.Fab")
		)
		(pad "1" smd custom
			(at 0 -0.762 180)
			(size 0.2159 0.2159)
			(layers "F.Cu" "F.Mask" "F.Paste")
			(net "P5V_USB")
			(options
				(clearance outline)
				(anchor circle)
			)
			(primitives
				(gr_poly
					(pts
						(arc
							(start -0.3302 -0.4318)
							(mid -0.402042 -0.402042)
							(end -0.4318 -0.3302)
						)
						(arc
							(start -0.4318 0.3302)
							(mid -0.402042 0.402042)
							(end -0.3302 0.4318)
						)
						(arc
							(start 0.3302 0.4318)
							(mid 0.402042 0.402042)
							(end 0.4318 0.3302)
						)
						(arc
							(start 0.4318 -0.3302)
							(mid 0.402042 -0.402042)
							(end 0.3302 -0.4318)
						)
					)
					(width 0)
					(fill yes)
				)
			)
		)
		(pad "2" smd custom
			(at 0 0.762 180)
			(size 0.2159 0.2159)
			(layers "F.Cu" "F.Mask" "F.Paste")
			(net "GND")
			(options
				(clearance outline)
				(anchor circle)
			)
			(primitives
				(gr_poly
					(pts
						(arc
							(start -0.3302 -0.4318)
							(mid -0.402042 -0.402042)
							(end -0.4318 -0.3302)
						)
						(arc
							(start -0.4318 0.3302)
							(mid -0.402042 0.402042)
							(end -0.3302 0.4318)
						)
						(arc
							(start 0.3302 0.4318)
							(mid 0.402042 0.402042)
							(end 0.4318 0.3302)
						)
						(arc
							(start 0.4318 -0.3302)
							(mid 0.402042 -0.402042)
							(end 0.3302 -0.4318)
						)
					)
					(width 0)
					(fill yes)
				)
			)
		)
	)
	(footprint ""
		(layer "F.Cu")
		(at 38.544246 -177.14341)
		(property "Reference" "R486"
			(at 0 0 0)
			(layer "F.SilkS")
			(hide yes)
			(effects
				(font
					(size 1.27 1.27)
				)
			)
		)
		(property "Value" "3K83R2F-GP"
			(at 0.064008 -3.993896 0)
			(unlocked yes)
			(layer "F.Fab")
			(hide yes)
			(effects
				(font
					(size 1.016 1.016)
					(thickness 0.1524)
				)
			)
		)
		(property "Device Type" "R402H16"
			(at 0.064008 -5.517896 0)
			(unlocked yes)
			(layer "F.Fab")
			(hide yes)
			(effects
				(font
					(size 1.016 1.016)
					(thickness 0.1524)
				)
			)
		)
		(duplicate_pad_numbers_are_jumpers no)
		(fp_line
			(start -0.508 -0.9398)
			(end -0.508 0.9398)
			(stroke
				(width 0.1524)
				(type default)
			)
			(layer "F.SilkS")
		)
		(fp_line
			(start 0.508 -0.9398)
			(end -0.508 -0.9398)
			(stroke
				(width 0.1524)
				(type default)
			)
			(layer "F.SilkS")
		)
		(fp_rect
			(start -0.508 0.9398)
			(end 0.508 -0.9398)
			(stroke
				(width 0)
				(type default)
			)
			(fill no)
			(layer "F.CrtYd")
		)
		(fp_rect
			(start -0.508 0.9398)
			(end 0.508 -0.9398)
			(stroke
				(width 0)
				(type default)
			)
			(fill no)
			(layer "F.Fab")
		)
		(pad "1" smd custom
			(at 0 -0.4445)
			(size 0.1397 0.1397)
			(layers "F.Cu" "F.Mask" "F.Paste")
			(net "P3V3_STBY_EN")
			(options
				(clearance outline)
				(anchor circle)
			)
			(primitives
				(gr_poly
					(pts
						(arc
							(start -0.1778 -0.2794)
							(mid -0.249642 -0.249642)
							(end -0.2794 -0.1778)
						)
						(arc
							(start -0.2794 0.1778)
							(mid -0.249642 0.249642)
							(end -0.1778 0.2794)
						)
						(arc
							(start 0.1778 0.2794)
							(mid 0.249642 0.249642)
							(end 0.2794 0.1778)
						)
						(arc
							(start 0.2794 -0.1778)
							(mid 0.249642 -0.249642)
							(end 0.1778 -0.2794)
						)
					)
					(width 0)
					(fill yes)
				)
			)
		)
		(pad "2" smd custom
			(at 0 0.4445)
			(size 0.1397 0.1397)
			(layers "F.Cu" "F.Mask" "F.Paste")
			(net "GND")
			(options
				(clearance outline)
				(anchor circle)
			)
			(primitives
				(gr_poly
					(pts
						(arc
							(start -0.1778 -0.2794)
							(mid -0.249642 -0.249642)
							(end -0.2794 -0.1778)
						)
						(arc
							(start -0.2794 0.1778)
							(mid -0.249642 0.249642)
							(end -0.1778 0.2794)
						)
						(arc
							(start 0.1778 0.2794)
							(mid 0.249642 0.249642)
							(end 0.2794 0.1778)
						)
						(arc
							(start 0.2794 -0.1778)
							(mid 0.249642 -0.249642)
							(end 0.1778 -0.2794)
						)
					)
					(width 0)
					(fill yes)
				)
			)
		)
	)
	(footprint ""
		(layer "F.Cu")
		(at 82.08645 -172.324522 -90)
		(property "Reference" "R451"
			(at 0 0 270)
			(layer "F.SilkS")
			(hide yes)
			(effects
				(font
					(size 1.27 1.27)
				)
			)
		)
		(property "Value" "10KR2F-2-GP"
			(at 0.064008 -3.993896 270)
			(unlocked yes)
			(layer "F.Fab")
			(hide yes)
			(effects
				(font
					(size 1.016 1.016)
					(thickness 0.1524)
				)
			)
		)
		(property "Device Type" "R402H16"
			(at 0.064008 -5.517896 270)
			(unlocked yes)
			(layer "F.Fab")
			(hide yes)
			(effects
				(font
					(size 1.016 1.016)
					(thickness 0.1524)
				)
			)
		)
		(duplicate_pad_numbers_are_jumpers no)
		(fp_line
			(start -0.508 -0.9398)
			(end -0.508 0.9398)
			(stroke
				(width 0.1524)
				(type default)
			)
			(layer "F.SilkS")
		)
		(fp_line
			(start 0.508 -0.9398)
			(end -0.508 -0.9398)
			(stroke
				(width 0.1524)
				(type default)
			)
			(layer "F.SilkS")
		)
		(fp_rect
			(start -0.508 0.9398)
			(end 0.508 -0.9398)
			(stroke
				(width 0)
				(type default)
			)
			(fill no)
			(layer "F.CrtYd")
		)
		(fp_rect
			(start -0.508 0.9398)
			(end 0.508 -0.9398)
			(stroke
				(width 0)
				(type default)
			)
			(fill no)
			(layer "F.Fab")
		)
		(pad "1" smd custom
			(at 0 -0.4445 270)
			(size 0.1397 0.1397)
			(layers "F.Cu" "F.Mask" "F.Paste")
			(net "EXP_UART_EN_R")
			(options
				(clearance outline)
				(anchor circle)
			)
			(primitives
				(gr_poly
					(pts
						(arc
							(start -0.1778 -0.2794)
							(mid -0.249642 -0.249642)
							(end -0.2794 -0.1778)
						)
						(arc
							(start -0.2794 0.1778)
							(mid -0.249642 0.249642)
							(end -0.1778 0.2794)
						)
						(arc
							(start 0.1778 0.2794)
							(mid 0.249642 0.249642)
							(end 0.2794 0.1778)
						)
						(arc
							(start 0.2794 -0.1778)
							(mid 0.249642 -0.249642)
							(end 0.1778 -0.2794)
						)
					)
					(width 0)
					(fill yes)
				)
			)
		)
		(pad "2" smd custom
			(at 0 0.4445 270)
			(size 0.1397 0.1397)
			(layers "F.Cu" "F.Mask" "F.Paste")
			(net "GND")
			(options
				(clearance outline)
				(anchor circle)
			)
			(primitives
				(gr_poly
					(pts
						(arc
							(start -0.1778 -0.2794)
							(mid -0.249642 -0.249642)
							(end -0.2794 -0.1778)
						)
						(arc
							(start -0.2794 0.1778)
							(mid -0.249642 0.249642)
							(end -0.1778 0.2794)
						)
						(arc
							(start 0.1778 0.2794)
							(mid 0.249642 0.249642)
							(end 0.2794 0.1778)
						)
						(arc
							(start 0.2794 -0.1778)
							(mid 0.249642 -0.249642)
							(end 0.1778 -0.2794)
						)
					)
					(width 0)
					(fill yes)
				)
			)
		)
	)
	(footprint ""
		(layer "F.Cu")
		(at 124.841 -10.668 90)
		(property "Reference" "R439"
			(at 0 0 90)
			(layer "F.SilkS")
			(hide yes)
			(effects
				(font
					(size 1.27 1.27)
				)
			)
		)
		(property "Value" "11KR2F-L-GP"
			(at 0.064008 -3.993896 90)
			(unlocked yes)
			(layer "F.Fab")
			(hide yes)
			(effects
				(font
					(size 1.016 1.016)
					(thickness 0.1524)
				)
			)
		)
		(property "Device Type" "R402H16"
			(at 0.064008 -5.517896 90)
			(unlocked yes)
			(layer "F.Fab")
			(hide yes)
			(effects
				(font
					(size 1.016 1.016)
					(thickness 0.1524)
				)
			)
		)
		(duplicate_pad_numbers_are_jumpers no)
		(fp_line
			(start 0.508 -0.9398)
			(end -0.508 -0.9398)
			(stroke
				(width 0.1524)
				(type default)
			)
			(layer "F.SilkS")
		)
		(fp_line
			(start -0.508 -0.9398)
			(end -0.508 0.9398)
			(stroke
				(width 0.1524)
				(type default)
			)
			(layer "F.SilkS")
		)
		(fp_rect
			(start -0.508 0.9398)
			(end 0.508 -0.9398)
			(stroke
				(width 0)
				(type default)
			)
			(fill no)
			(layer "F.CrtYd")
		)
		(fp_rect
			(start -0.508 0.9398)
			(end 0.508 -0.9398)
			(stroke
				(width 0)
				(type default)
			)
			(fill no)
			(layer "F.Fab")
		)
		(pad "1" smd custom
			(at 0 -0.4445 90)
			(size 0.1397 0.1397)
			(layers "F.Cu" "F.Mask" "F.Paste")
			(net "MB0_P12V_PWGIN_R")
			(options
				(clearance outline)
				(anchor circle)
			)
			(primitives
				(gr_poly
					(pts
						(arc
							(start -0.1778 -0.2794)
							(mid -0.249642 -0.249642)
							(end -0.2794 -0.1778)
						)
						(arc
							(start -0.2794 0.1778)
							(mid -0.249642 0.249642)
							(end -0.1778 0.2794)
						)
						(arc
							(start 0.1778 0.2794)
							(mid 0.249642 0.249642)
							(end 0.2794 0.1778)
						)
						(arc
							(start 0.2794 -0.1778)
							(mid 0.249642 -0.249642)
							(end 0.1778 -0.2794)
						)
					)
					(width 0)
					(fill yes)
				)
			)
		)
		(pad "2" smd custom
			(at 0 0.4445 90)
			(size 0.1397 0.1397)
			(layers "F.Cu" "F.Mask" "F.Paste")
			(net "AGND_CURRENT_MON")
			(options
				(clearance outline)
				(anchor circle)
			)
			(primitives
				(gr_poly
					(pts
						(arc
							(start -0.1778 -0.2794)
							(mid -0.249642 -0.249642)
							(end -0.2794 -0.1778)
						)
						(arc
							(start -0.2794 0.1778)
							(mid -0.249642 0.249642)
							(end -0.1778 0.2794)
						)
						(arc
							(start 0.1778 0.2794)
							(mid 0.249642 0.249642)
							(end 0.2794 0.1778)
						)
						(arc
							(start 0.2794 -0.1778)
							(mid 0.249642 -0.249642)
							(end 0.1778 -0.2794)
						)
					)
					(width 0)
					(fill yes)
				)
			)
		)
	)
	(footprint ""
		(layer "F.Cu")
		(at 87.1474 -168.275 -90)
		(property "Reference" "Q12"
			(at 0 0 270)
			(layer "F.SilkS")
			(hide yes)
			(effects
				(font
					(size 1.27 1.27)
				)
			)
		)
		(property "Value" "2N7002K-1-GP"
			(at 0.127 -8.9662 270)
			(unlocked yes)
			(layer "F.Fab")
			(hide yes)
			(effects
				(font
					(size 1.016 1.016)
					(thickness 0.1524)
				)
			)
		)
		(property "Device Type" "SOT23DGS2D4H44"
			(at 0.127 -10.4902 270)
			(unlocked yes)
			(layer "F.Fab")
			(hide yes)
			(effects
				(font
					(size 1.016 1.016)
					(thickness 0.1524)
				)
			)
		)
		(duplicate_pad_numbers_are_jumpers no)
		(fp_line
			(start -1.651 1.778)
			(end 1.651 1.778)
			(stroke
				(width 0.1524)
				(type default)
			)
			(layer "F.SilkS")
		)
		(fp_line
			(start 1.651 1.778)
			(end 1.651 -1.778)
			(stroke
				(width 0.1524)
				(type default)
			)
			(layer "F.SilkS")
		)
		(fp_line
			(start -1.651 -1.778)
			(end -1.651 1.778)
			(stroke
				(width 0.1524)
				(type default)
			)
			(layer "F.SilkS")
		)
		(fp_line
			(start 1.651 -1.778)
			(end -1.651 -1.778)
			(stroke
				(width 0.1524)
				(type default)
			)
			(layer "F.SilkS")
		)
		(fp_poly
			(pts
				(xy -1.778 1.8796) (xy -1.778 -1.8796) (xy 1.778 -1.8796) (xy 1.778 1.8796)
			)
			(stroke
				(width 0)
				(type default)
			)
			(fill no)
			(layer "F.CrtYd")
		)
		(fp_poly
			(pts
				(xy -1.778 1.8796) (xy -1.778 -1.8796) (xy 1.778 -1.8796) (xy 1.778 1.8796)
			)
			(stroke
				(width 0)
				(type default)
			)
			(fill no)
			(layer "F.Fab")
		)
		(pad "D" smd custom
			(at 0 -0.9525 270)
			(size 0.1905 0.1905)
			(layers "F.Cu" "F.Mask" "F.Paste")
			(net "IOM_STBY_PGOOD")
			(options
				(clearance outline)
				(anchor circle)
			)
			(primitives
				(gr_poly
					(pts
						(arc
							(start -0.1778 0.5715)
							(mid -0.321484 0.511984)
							(end -0.381 0.3683)
						)
						(arc
							(start -0.381 -0.3683)
							(mid -0.321484 -0.511984)
							(end -0.1778 -0.5715)
						)
						(arc
							(start 0.1778 -0.5715)
							(mid 0.321484 -0.511984)
							(end 0.381 -0.3683)
						)
						(arc
							(start 0.381 0.3683)
							(mid 0.321484 0.511984)
							(end 0.1778 0.5715)
						)
					)
					(width 0)
					(fill yes)
				)
			)
		)
		(pad "G" smd custom
			(at -0.98425 0.9525 270)
			(size 0.1905 0.1905)
			(layers "F.Cu" "F.Mask" "F.Paste")
			(net "P1V15_STBY_PG_G")
			(options
				(clearance outline)
				(anchor circle)
			)
			(primitives
				(gr_poly
					(pts
						(arc
							(start -0.1778 0.5715)
							(mid -0.321484 0.511984)
							(end -0.381 0.3683)
						)
						(arc
							(start -0.381 -0.3683)
							(mid -0.321484 -0.511984)
							(end -0.1778 -0.5715)
						)
						(arc
							(start 0.1778 -0.5715)
							(mid 0.321484 -0.511984)
							(end 0.381 -0.3683)
						)
						(arc
							(start 0.381 0.3683)
							(mid 0.321484 0.511984)
							(end 0.1778 0.5715)
						)
					)
					(width 0)
					(fill yes)
				)
			)
		)
		(pad "S" smd custom
			(at 0.98425 0.9525 270)
			(size 0.1905 0.1905)
			(layers "F.Cu" "F.Mask" "F.Paste")
			(net "GND")
			(options
				(clearance outline)
				(anchor circle)
			)
			(primitives
				(gr_poly
					(pts
						(arc
							(start -0.1778 0.5715)
							(mid -0.321484 0.511984)
							(end -0.381 0.3683)
						)
						(arc
							(start -0.381 -0.3683)
							(mid -0.321484 -0.511984)
							(end -0.1778 -0.5715)
						)
						(arc
							(start 0.1778 -0.5715)
							(mid 0.321484 -0.511984)
							(end 0.381 -0.3683)
						)
						(arc
							(start 0.381 0.3683)
							(mid 0.321484 0.511984)
							(end 0.1778 0.5715)
						)
					)
					(width 0)
					(fill yes)
				)
			)
		)
	)
	(footprint ""
		(layer "F.Cu")
		(at 215.470994 -43.047412 -90)
		(property "Reference" "R465"
			(at 0 0 270)
			(layer "F.SilkS")
			(hide yes)
			(effects
				(font
					(size 1.27 1.27)
				)
			)
		)
		(property "Value" "2K2R2F-GP"
			(at 0.064008 -3.993896 270)
			(unlocked yes)
			(layer "F.Fab")
			(hide yes)
			(effects
				(font
					(size 1.016 1.016)
					(thickness 0.1524)
				)
			)
		)
		(property "Device Type" "R402H16"
			(at 0.064008 -5.517896 270)
			(unlocked yes)
			(layer "F.Fab")
			(hide yes)
			(effects
				(font
					(size 1.016 1.016)
					(thickness 0.1524)
				)
			)
		)
		(duplicate_pad_numbers_are_jumpers no)
		(fp_line
			(start -0.508 -0.9398)
			(end -0.508 0.9398)
			(stroke
				(width 0.1524)
				(type default)
			)
			(layer "F.SilkS")
		)
		(fp_line
			(start 0.508 -0.9398)
			(end -0.508 -0.9398)
			(stroke
				(width 0.1524)
				(type default)
			)
			(layer "F.SilkS")
		)
		(fp_rect
			(start -0.508 0.9398)
			(end 0.508 -0.9398)
			(stroke
				(width 0)
				(type default)
			)
			(fill no)
			(layer "F.CrtYd")
		)
		(fp_rect
			(start -0.508 0.9398)
			(end 0.508 -0.9398)
			(stroke
				(width 0)
				(type default)
			)
			(fill no)
			(layer "F.Fab")
		)
		(pad "1" smd custom
			(at 0 -0.4445 270)
			(size 0.1397 0.1397)
			(layers "F.Cu" "F.Mask" "F.Paste")
			(net "P5V_EN_R")
			(options
				(clearance outline)
				(anchor circle)
			)
			(primitives
				(gr_poly
					(pts
						(arc
							(start -0.1778 -0.2794)
							(mid -0.249642 -0.249642)
							(end -0.2794 -0.1778)
						)
						(arc
							(start -0.2794 0.1778)
							(mid -0.249642 0.249642)
							(end -0.1778 0.2794)
						)
						(arc
							(start 0.1778 0.2794)
							(mid 0.249642 0.249642)
							(end 0.2794 0.1778)
						)
						(arc
							(start 0.2794 -0.1778)
							(mid 0.249642 -0.249642)
							(end 0.1778 -0.2794)
						)
					)
					(width 0)
					(fill yes)
				)
			)
		)
		(pad "2" smd custom
			(at 0 0.4445 270)
			(size 0.1397 0.1397)
			(layers "F.Cu" "F.Mask" "F.Paste")
			(net "GND")
			(options
				(clearance outline)
				(anchor circle)
			)
			(primitives
				(gr_poly
					(pts
						(arc
							(start -0.1778 -0.2794)
							(mid -0.249642 -0.249642)
							(end -0.2794 -0.1778)
						)
						(arc
							(start -0.2794 0.1778)
							(mid -0.249642 0.249642)
							(end -0.1778 0.2794)
						)
						(arc
							(start 0.1778 0.2794)
							(mid 0.249642 0.249642)
							(end 0.2794 0.1778)
						)
						(arc
							(start 0.2794 -0.1778)
							(mid 0.249642 -0.249642)
							(end 0.1778 -0.2794)
						)
					)
					(width 0)
					(fill yes)
				)
			)
		)
	)
	(footprint ""
		(layer "F.Cu")
		(at 214.78875 -45.561758)
		(property "Reference" "C163"
			(at 0 0 0)
			(layer "F.SilkS")
			(hide yes)
			(effects
				(font
					(size 1.27 1.27)
				)
			)
		)
		(property "Value" "SC68P50V2JN-2-GP"
			(at 1.1811 -2.7051 0)
			(unlocked yes)
			(layer "F.Fab")
			(hide yes)
			(effects
				(font
					(size 1.016 1.016)
					(thickness 0.1524)
				)
			)
		)
		(property "Device Type" "C402H22"
			(at 1.1811 -4.2291 0)
			(unlocked yes)
			(layer "F.Fab")
			(hide yes)
			(effects
				(font
					(size 1.016 1.016)
					(thickness 0.1524)
				)
			)
		)
		(duplicate_pad_numbers_are_jumpers no)
		(fp_rect
			(start -0.4318 0.9525)
			(end 0.4318 -0.9525)
			(stroke
				(width 0)
				(type default)
			)
			(fill no)
			(layer "F.CrtYd")
		)
		(fp_rect
			(start -0.4318 0.9525)
			(end 0.4318 -0.9525)
			(stroke
				(width 0)
				(type default)
			)
			(fill no)
			(layer "F.Fab")
		)
		(pad "1" smd custom
			(at 0 -0.4445)
			(size 0.1524 0.1524)
			(layers "F.Cu" "F.Mask" "F.Paste")
			(net "P5V_VFB")
			(options
				(clearance outline)
				(anchor circle)
			)
			(primitives
				(gr_poly
					(pts
						(arc
							(start 0.3048 -0.2032)
							(mid 0.275042 -0.275042)
							(end 0.2032 -0.3048)
						)
						(arc
							(start -0.2032 -0.3048)
							(mid -0.275042 -0.275042)
							(end -0.3048 -0.2032)
						)
						(arc
							(start -0.3048 0.2032)
							(mid -0.275042 0.275042)
							(end -0.2032 0.3048)
						)
						(arc
							(start 0.2032 0.3048)
							(mid 0.275042 0.275042)
							(end 0.3048 0.2032)
						)
					)
					(width 0)
					(fill yes)
				)
			)
		)
		(pad "2" smd custom
			(at 0 0.4445)
			(size 0.1524 0.1524)
			(layers "F.Cu" "F.Mask" "F.Paste")
			(net "P5V_VFB_R")
			(options
				(clearance outline)
				(anchor circle)
			)
			(primitives
				(gr_poly
					(pts
						(arc
							(start 0.3048 -0.2032)
							(mid 0.275042 -0.275042)
							(end 0.2032 -0.3048)
						)
						(arc
							(start -0.2032 -0.3048)
							(mid -0.275042 -0.275042)
							(end -0.3048 -0.2032)
						)
						(arc
							(start -0.3048 0.2032)
							(mid -0.275042 0.275042)
							(end -0.2032 0.3048)
						)
						(arc
							(start 0.2032 0.3048)
							(mid 0.275042 0.275042)
							(end 0.3048 0.2032)
						)
					)
					(width 0)
					(fill yes)
				)
			)
		)
	)
)
